(kicad_pcb
	(version 20260206)
	(generator "pcbnew")
	(generator_version "10.0")
	(general
		(thickness 1.6)
		(legacy_teardrops no)
	)
	(paper "A4")
	(title_block
		(title "04192023_DAF0TMB3IC0_F0TG_MB_C_brd_V02_OCP.brd")
		(comment 1 "Grand Teton / footprints 1518-1524 of 8354")
	)
	(layers
		(0 "F.Cu" signal "TOP")
		(4 "In1.Cu" signal "GND")
		(6 "In2.Cu" signal "IN1")
		(8 "In3.Cu" signal "GND1")
		(10 "In4.Cu" signal "IN2")
		(12 "In5.Cu" signal "GND2")
		(14 "In6.Cu" signal "IN3")
		(16 "In7.Cu" signal "GND3")
		(18 "In8.Cu" signal "VCC")
		(20 "In9.Cu" signal "VCC1")
		(22 "In10.Cu" signal "GND4")
		(24 "In11.Cu" signal "IN4")
		(26 "In12.Cu" signal "GND5")
		(28 "In13.Cu" signal "IN5")
		(30 "In14.Cu" signal "GND6")
		(32 "In15.Cu" signal "IN6")
		(34 "In16.Cu" signal "GND7")
		(2 "B.Cu" signal "BOTTOM")
		(9 "F.Adhes" user "F.Adhesive")
		(11 "B.Adhes" user "B.Adhesive")
		(13 "F.Paste" user "Package Geometry/Pastemask Top")
		(15 "B.Paste" user "Package Geometry/Pastemask Bottom")
		(5 "F.SilkS" user "Ref Des/Silkscreen Top")
		(7 "B.SilkS" user "Ref Des/Silkscreen Bottom")
		(1 "F.Mask" user "Board Geometry/Soldermask Top")
		(3 "B.Mask" user "Board Geometry/Soldermask Bottom")
		(17 "Dwgs.User" user "User.Drawings")
		(19 "Cmts.User" user "User.Comments")
		(21 "Eco1.User" user "User.Eco1")
		(23 "Eco2.User" user "User.Eco2")
		(25 "Edge.Cuts" user "Board Geometry/Outline")
		(27 "Margin" user)
		(31 "F.CrtYd" user "Package Geometry/Place Bound Top")
		(29 "B.CrtYd" user "Package Geometry/Place Bound Bottom")
		(35 "F.Fab" user "Ref Des/Assembly Top")
		(33 "B.Fab" user "Ref Des/Assembly Bottom")
	)
	(footprint ""
		(layer "F.Cu")
		(at 37.211 -365.125)
		(property "Reference" "PC357"
			(at 0 0 0)
			(layer "F.SilkS")
			(hide yes)
			(effects
				(font
					(size 1.27 1.27)
				)
			)
		)
		(property "Value" ""
			(at 0 0 0)
			(layer "F.Fab")
			(effects
				(font
					(size 1.27 1.27)
				)
			)
		)
		(duplicate_pad_numbers_are_jumpers no)
		(fp_line
			(start -0.7874 -0.4064)
			(end 0.7874 -0.4064)
			(stroke
				(width 0.1524)
				(type default)
			)
			(layer "F.SilkS")
		)
		(fp_line
			(start -0.7874 0.4064)
			(end -0.7874 -0.4064)
			(stroke
				(width 0.1524)
				(type default)
			)
			(layer "F.SilkS")
		)
		(fp_line
			(start 0.7874 -0.4064)
			(end 0.7874 0.4064)
			(stroke
				(width 0.1524)
				(type default)
			)
			(layer "F.SilkS")
		)
		(fp_line
			(start 0.7874 0.4064)
			(end -0.7874 0.4064)
			(stroke
				(width 0.1524)
				(type default)
			)
			(layer "F.SilkS")
		)
		(fp_line
			(start -0.67945 -0.305054)
			(end -0.12065 -0.305054)
			(stroke
				(width 0.1)
				(type default)
			)
			(layer "F.Fab")
		)
		(fp_line
			(start -0.67945 0.3048)
			(end -0.67945 -0.305054)
			(stroke
				(width 0.1)
				(type default)
			)
			(layer "F.Fab")
		)
		(fp_line
			(start -0.12065 -0.305054)
			(end -0.12065 -0.2794)
			(stroke
				(width 0.1)
				(type default)
			)
			(layer "F.Fab")
		)
		(fp_line
			(start -0.12065 -0.2794)
			(end 0.12065 -0.2794)
			(stroke
				(width 0.1)
				(type default)
			)
			(layer "F.Fab")
		)
		(fp_line
			(start -0.12065 0.2794)
			(end -0.12065 0.3048)
			(stroke
				(width 0.1)
				(type default)
			)
			(layer "F.Fab")
		)
		(fp_line
			(start -0.12065 0.3048)
			(end -0.67945 0.3048)
			(stroke
				(width 0.1)
				(type default)
			)
			(layer "F.Fab")
		)
		(fp_line
			(start 0.120396 0.2794)
			(end -0.12065 0.2794)
			(stroke
				(width 0.1)
				(type default)
			)
			(layer "F.Fab")
		)
		(fp_line
			(start 0.120396 0.3048)
			(end 0.120396 0.2794)
			(stroke
				(width 0.1)
				(type default)
			)
			(layer "F.Fab")
		)
		(fp_line
			(start 0.12065 -0.3048)
			(end 0.67945 -0.3048)
			(stroke
				(width 0.1)
				(type default)
			)
			(layer "F.Fab")
		)
		(fp_line
			(start 0.12065 -0.2794)
			(end 0.12065 -0.3048)
			(stroke
				(width 0.1)
				(type default)
			)
			(layer "F.Fab")
		)
		(fp_line
			(start 0.67945 -0.3048)
			(end 0.67945 0.3048)
			(stroke
				(width 0.1)
				(type default)
			)
			(layer "F.Fab")
		)
		(fp_line
			(start 0.67945 0.3048)
			(end 0.120396 0.3048)
			(stroke
				(width 0.1)
				(type default)
			)
			(layer "F.Fab")
		)
		(pad "1" smd circle
			(at -0.40005 0)
			(size 0 0)
			(layers "F.Cu" "F.Mask" "F.Paste")
			(net "PVDDCR_CPU1_P1_VMON")
		)
		(pad "2" smd circle
			(at 0.40005 0)
			(size 0 0)
			(layers "F.Cu" "F.Mask" "F.Paste")
			(net "GND")
		)
	)
	(footprint ""
		(layer "F.Cu")
		(at 12.876784 -392.650726 90)
		(property "Reference" "PR6626"
			(at 0 0 90)
			(layer "F.SilkS")
			(hide yes)
			(effects
				(font
					(size 1.27 1.27)
				)
			)
		)
		(property "Value" ""
			(at 0 0 90)
			(layer "F.Fab")
			(effects
				(font
					(size 1.27 1.27)
				)
			)
		)
		(duplicate_pad_numbers_are_jumpers no)
		(fp_line
			(start 0.7874 -0.4064)
			(end 0.7874 0.4064)
			(stroke
				(width 0.1524)
				(type default)
			)
			(layer "F.SilkS")
		)
		(fp_line
			(start -0.7874 -0.4064)
			(end 0.7874 -0.4064)
			(stroke
				(width 0.1524)
				(type default)
			)
			(layer "F.SilkS")
		)
		(fp_line
			(start -0.7874 -0.202184)
			(end -0.7874 -0.4064)
			(stroke
				(width 0.1524)
				(type default)
			)
			(layer "F.SilkS")
		)
		(fp_line
			(start 0.7874 0.4064)
			(end -0.271526 0.4064)
			(stroke
				(width 0.1524)
				(type default)
			)
			(layer "F.SilkS")
		)
		(fp_line
			(start -0.12065 -0.305054)
			(end -0.12065 -0.2794)
			(stroke
				(width 0.1)
				(type default)
			)
			(layer "F.Fab")
		)
		(fp_line
			(start -0.67945 -0.305054)
			(end -0.12065 -0.305054)
			(stroke
				(width 0.1)
				(type default)
			)
			(layer "F.Fab")
		)
		(fp_line
			(start 0.67945 -0.3048)
			(end 0.67945 0.3048)
			(stroke
				(width 0.1)
				(type default)
			)
			(layer "F.Fab")
		)
		(fp_line
			(start 0.12065 -0.3048)
			(end 0.67945 -0.3048)
			(stroke
				(width 0.1)
				(type default)
			)
			(layer "F.Fab")
		)
		(fp_line
			(start 0.12065 -0.2794)
			(end 0.12065 -0.3048)
			(stroke
				(width 0.1)
				(type default)
			)
			(layer "F.Fab")
		)
		(fp_line
			(start -0.12065 -0.2794)
			(end 0.12065 -0.2794)
			(stroke
				(width 0.1)
				(type default)
			)
			(layer "F.Fab")
		)
		(fp_line
			(start 0.120396 0.2794)
			(end -0.12065 0.2794)
			(stroke
				(width 0.1)
				(type default)
			)
			(layer "F.Fab")
		)
		(fp_line
			(start -0.12065 0.2794)
			(end -0.12065 0.3048)
			(stroke
				(width 0.1)
				(type default)
			)
			(layer "F.Fab")
		)
		(fp_line
			(start 0.67945 0.3048)
			(end 0.120396 0.3048)
			(stroke
				(width 0.1)
				(type default)
			)
			(layer "F.Fab")
		)
		(fp_line
			(start 0.120396 0.3048)
			(end 0.120396 0.2794)
			(stroke
				(width 0.1)
				(type default)
			)
			(layer "F.Fab")
		)
		(fp_line
			(start -0.12065 0.3048)
			(end -0.67945 0.3048)
			(stroke
				(width 0.1)
				(type default)
			)
			(layer "F.Fab")
		)
		(fp_line
			(start -0.67945 0.3048)
			(end -0.67945 -0.305054)
			(stroke
				(width 0.1)
				(type default)
			)
			(layer "F.Fab")
		)
		(pad "1" smd circle
			(at -0.40005 0 90)
			(size 0 0)
			(layers "F.Cu" "F.Mask" "F.Paste")
			(net "P0V9_RETIMER_CPU1_VOS1")
		)
		(pad "2" smd circle
			(at 0.40005 0 90)
			(size 0 0)
			(layers "F.Cu" "F.Mask" "F.Paste")
			(net "P0V9_CPU1_RT_2D")
		)
	)
	(footprint ""
		(layer "F.Cu")
		(at 403.682962 -54.4195 180)
		(property "Reference" "R1528"
			(at 0 0 180)
			(layer "F.SilkS")
			(hide yes)
			(effects
				(font
					(size 1.27 1.27)
				)
			)
		)
		(property "Value" ""
			(at 0 0 180)
			(layer "F.Fab")
			(effects
				(font
					(size 1.27 1.27)
				)
			)
		)
		(duplicate_pad_numbers_are_jumpers no)
		(fp_line
			(start 0.7874 0.4064)
			(end -0.7874 0.4064)
			(stroke
				(width 0.1524)
				(type default)
			)
			(layer "F.SilkS")
		)
		(fp_line
			(start 0.7874 -0.4064)
			(end 0.7874 0.4064)
			(stroke
				(width 0.1524)
				(type default)
			)
			(layer "F.SilkS")
		)
		(fp_line
			(start -0.7874 0.4064)
			(end -0.7874 -0.4064)
			(stroke
				(width 0.1524)
				(type default)
			)
			(layer "F.SilkS")
		)
		(fp_line
			(start -0.7874 -0.4064)
			(end 0.7874 -0.4064)
			(stroke
				(width 0.1524)
				(type default)
			)
			(layer "F.SilkS")
		)
		(fp_line
			(start 0.67945 0.3048)
			(end 0.120396 0.3048)
			(stroke
				(width 0.1)
				(type default)
			)
			(layer "F.Fab")
		)
		(fp_line
			(start 0.67945 -0.3048)
			(end 0.67945 0.3048)
			(stroke
				(width 0.1)
				(type default)
			)
			(layer "F.Fab")
		)
		(fp_line
			(start 0.12065 -0.2794)
			(end 0.12065 -0.3048)
			(stroke
				(width 0.1)
				(type default)
			)
			(layer "F.Fab")
		)
		(fp_line
			(start 0.12065 -0.3048)
			(end 0.67945 -0.3048)
			(stroke
				(width 0.1)
				(type default)
			)
			(layer "F.Fab")
		)
		(fp_line
			(start 0.120396 0.3048)
			(end 0.120396 0.2794)
			(stroke
				(width 0.1)
				(type default)
			)
			(layer "F.Fab")
		)
		(fp_line
			(start 0.120396 0.2794)
			(end -0.12065 0.2794)
			(stroke
				(width 0.1)
				(type default)
			)
			(layer "F.Fab")
		)
		(fp_line
			(start -0.12065 0.3048)
			(end -0.67945 0.3048)
			(stroke
				(width 0.1)
				(type default)
			)
			(layer "F.Fab")
		)
		(fp_line
			(start -0.12065 0.2794)
			(end -0.12065 0.3048)
			(stroke
				(width 0.1)
				(type default)
			)
			(layer "F.Fab")
		)
		(fp_line
			(start -0.12065 -0.2794)
			(end 0.12065 -0.2794)
			(stroke
				(width 0.1)
				(type default)
			)
			(layer "F.Fab")
		)
		(fp_line
			(start -0.12065 -0.305054)
			(end -0.12065 -0.2794)
			(stroke
				(width 0.1)
				(type default)
			)
			(layer "F.Fab")
		)
		(fp_line
			(start -0.67945 0.3048)
			(end -0.67945 -0.305054)
			(stroke
				(width 0.1)
				(type default)
			)
			(layer "F.Fab")
		)
		(fp_line
			(start -0.67945 -0.305054)
			(end -0.12065 -0.305054)
			(stroke
				(width 0.1)
				(type default)
			)
			(layer "F.Fab")
		)
		(pad "1" smd circle
			(at -0.40005 0 180)
			(size 0 0)
			(layers "F.Cu" "F.Mask" "F.Paste")
			(net "PRSNT_HDT_N")
		)
		(pad "2" smd circle
			(at 0.40005 0 180)
			(size 0 0)
			(layers "F.Cu" "F.Mask" "F.Paste")
			(net "PRSNT_HDT_R_N")
		)
	)
	(footprint ""
		(layer "F.Cu")
		(at 150.31974 -102.688898)
		(property "Reference" "R3295"
			(at 0 0 0)
			(layer "F.SilkS")
			(hide yes)
			(effects
				(font
					(size 1.27 1.27)
				)
			)
		)
		(property "Value" ""
			(at 0 0 0)
			(layer "F.Fab")
			(effects
				(font
					(size 1.27 1.27)
				)
			)
		)
		(duplicate_pad_numbers_are_jumpers no)
		(fp_line
			(start -0.7874 -0.4064)
			(end 0.7874 -0.4064)
			(stroke
				(width 0.1524)
				(type default)
			)
			(layer "F.SilkS")
		)
		(fp_line
			(start -0.7874 0.4064)
			(end -0.7874 -0.4064)
			(stroke
				(width 0.1524)
				(type default)
			)
			(layer "F.SilkS")
		)
		(fp_line
			(start 0.7874 -0.4064)
			(end 0.7874 0.4064)
			(stroke
				(width 0.1524)
				(type default)
			)
			(layer "F.SilkS")
		)
		(fp_line
			(start 0.7874 0.4064)
			(end -0.7874 0.4064)
			(stroke
				(width 0.1524)
				(type default)
			)
			(layer "F.SilkS")
		)
		(fp_line
			(start -0.67945 -0.305054)
			(end -0.12065 -0.305054)
			(stroke
				(width 0.1)
				(type default)
			)
			(layer "F.Fab")
		)
		(fp_line
			(start -0.67945 0.3048)
			(end -0.67945 -0.305054)
			(stroke
				(width 0.1)
				(type default)
			)
			(layer "F.Fab")
		)
		(fp_line
			(start -0.12065 -0.305054)
			(end -0.12065 -0.2794)
			(stroke
				(width 0.1)
				(type default)
			)
			(layer "F.Fab")
		)
		(fp_line
			(start -0.12065 -0.2794)
			(end 0.12065 -0.2794)
			(stroke
				(width 0.1)
				(type default)
			)
			(layer "F.Fab")
		)
		(fp_line
			(start -0.12065 0.2794)
			(end -0.12065 0.3048)
			(stroke
				(width 0.1)
				(type default)
			)
			(layer "F.Fab")
		)
		(fp_line
			(start -0.12065 0.3048)
			(end -0.67945 0.3048)
			(stroke
				(width 0.1)
				(type default)
			)
			(layer "F.Fab")
		)
		(fp_line
			(start 0.120396 0.2794)
			(end -0.12065 0.2794)
			(stroke
				(width 0.1)
				(type default)
			)
			(layer "F.Fab")
		)
		(fp_line
			(start 0.120396 0.3048)
			(end 0.120396 0.2794)
			(stroke
				(width 0.1)
				(type default)
			)
			(layer "F.Fab")
		)
		(fp_line
			(start 0.12065 -0.3048)
			(end 0.67945 -0.3048)
			(stroke
				(width 0.1)
				(type default)
			)
			(layer "F.Fab")
		)
		(fp_line
			(start 0.12065 -0.2794)
			(end 0.12065 -0.3048)
			(stroke
				(width 0.1)
				(type default)
			)
			(layer "F.Fab")
		)
		(fp_line
			(start 0.67945 -0.3048)
			(end 0.67945 0.3048)
			(stroke
				(width 0.1)
				(type default)
			)
			(layer "F.Fab")
		)
		(fp_line
			(start 0.67945 0.3048)
			(end 0.120396 0.3048)
			(stroke
				(width 0.1)
				(type default)
			)
			(layer "F.Fab")
		)
		(pad "1" smd circle
			(at -0.40005 0)
			(size 0 0)
			(layers "F.Cu" "F.Mask" "F.Paste")
			(net "P3V3_M2_0")
		)
		(pad "2" smd circle
			(at 0.40005 0)
			(size 0 0)
			(layers "F.Cu" "F.Mask" "F.Paste")
			(net "LED_HDD_ACTIVITY_N")
		)
	)
	(footprint ""
		(layer "F.Cu")
		(at 166.942516 -347.289882 180)
		(property "Reference" "PR464"
			(at 0 0 180)
			(layer "F.SilkS")
			(hide yes)
			(effects
				(font
					(size 1.27 1.27)
				)
			)
		)
		(property "Value" ""
			(at 0 0 180)
			(layer "F.Fab")
			(effects
				(font
					(size 1.27 1.27)
				)
			)
		)
		(duplicate_pad_numbers_are_jumpers no)
		(fp_line
			(start 0.7874 0.4064)
			(end -0.7874 0.4064)
			(stroke
				(width 0.1524)
				(type default)
			)
			(layer "F.SilkS")
		)
		(fp_line
			(start 0.7874 -0.4064)
			(end 0.7874 0.4064)
			(stroke
				(width 0.1524)
				(type default)
			)
			(layer "F.SilkS")
		)
		(fp_line
			(start -0.7874 0.4064)
			(end -0.7874 -0.4064)
			(stroke
				(width 0.1524)
				(type default)
			)
			(layer "F.SilkS")
		)
		(fp_line
			(start -0.7874 -0.4064)
			(end 0.7874 -0.4064)
			(stroke
				(width 0.1524)
				(type default)
			)
			(layer "F.SilkS")
		)
		(fp_line
			(start 0.67945 0.3048)
			(end 0.120396 0.3048)
			(stroke
				(width 0.1)
				(type default)
			)
			(layer "F.Fab")
		)
		(fp_line
			(start 0.67945 -0.3048)
			(end 0.67945 0.3048)
			(stroke
				(width 0.1)
				(type default)
			)
			(layer "F.Fab")
		)
		(fp_line
			(start 0.12065 -0.2794)
			(end 0.12065 -0.3048)
			(stroke
				(width 0.1)
				(type default)
			)
			(layer "F.Fab")
		)
		(fp_line
			(start 0.12065 -0.3048)
			(end 0.67945 -0.3048)
			(stroke
				(width 0.1)
				(type default)
			)
			(layer "F.Fab")
		)
		(fp_line
			(start 0.120396 0.3048)
			(end 0.120396 0.2794)
			(stroke
				(width 0.1)
				(type default)
			)
			(layer "F.Fab")
		)
		(fp_line
			(start 0.120396 0.2794)
			(end -0.12065 0.2794)
			(stroke
				(width 0.1)
				(type default)
			)
			(layer "F.Fab")
		)
		(fp_line
			(start -0.12065 0.3048)
			(end -0.67945 0.3048)
			(stroke
				(width 0.1)
				(type default)
			)
			(layer "F.Fab")
		)
		(fp_line
			(start -0.12065 0.2794)
			(end -0.12065 0.3048)
			(stroke
				(width 0.1)
				(type default)
			)
			(layer "F.Fab")
		)
		(fp_line
			(start -0.12065 -0.2794)
			(end 0.12065 -0.2794)
			(stroke
				(width 0.1)
				(type default)
			)
			(layer "F.Fab")
		)
		(fp_line
			(start -0.12065 -0.305054)
			(end -0.12065 -0.2794)
			(stroke
				(width 0.1)
				(type default)
			)
			(layer "F.Fab")
		)
		(fp_line
			(start -0.67945 0.3048)
			(end -0.67945 -0.305054)
			(stroke
				(width 0.1)
				(type default)
			)
			(layer "F.Fab")
		)
		(fp_line
			(start -0.67945 -0.305054)
			(end -0.12065 -0.305054)
			(stroke
				(width 0.1)
				(type default)
			)
			(layer "F.Fab")
		)
		(pad "1" smd circle
			(at -0.40005 0 180)
			(size 0 0)
			(layers "F.Cu" "F.Mask" "F.Paste")
			(net "GND")
		)
		(pad "2" smd circle
			(at 0.40005 0 180)
			(size 0 0)
			(layers "F.Cu" "F.Mask" "F.Paste")
			(net "PVDD11_S3_P1_ADDR_CFG")
		)
	)
	(footprint ""
		(layer "F.Cu")
		(at 305.819048 -40.890698 180)
		(property "Reference" "R3668"
			(at 0 0 180)
			(layer "F.SilkS")
			(hide yes)
			(effects
				(font
					(size 1.27 1.27)
				)
			)
		)
		(property "Value" ""
			(at 0 0 180)
			(layer "F.Fab")
			(effects
				(font
					(size 1.27 1.27)
				)
			)
		)
		(duplicate_pad_numbers_are_jumpers no)
		(fp_line
			(start 0.7874 0.4064)
			(end -0.7874 0.4064)
			(stroke
				(width 0.1524)
				(type default)
			)
			(layer "F.SilkS")
		)
		(fp_line
			(start 0.7874 -0.4064)
			(end 0.7874 0.4064)
			(stroke
				(width 0.1524)
				(type default)
			)
			(layer "F.SilkS")
		)
		(fp_line
			(start -0.7874 0.4064)
			(end -0.7874 -0.4064)
			(stroke
				(width 0.1524)
				(type default)
			)
			(layer "F.SilkS")
		)
		(fp_line
			(start -0.7874 -0.4064)
			(end 0.7874 -0.4064)
			(stroke
				(width 0.1524)
				(type default)
			)
			(layer "F.SilkS")
		)
		(fp_line
			(start 0.67945 0.3048)
			(end 0.120396 0.3048)
			(stroke
				(width 0.1)
				(type default)
			)
			(layer "F.Fab")
		)
		(fp_line
			(start 0.67945 -0.3048)
			(end 0.67945 0.3048)
			(stroke
				(width 0.1)
				(type default)
			)
			(layer "F.Fab")
		)
		(fp_line
			(start 0.12065 -0.2794)
			(end 0.12065 -0.3048)
			(stroke
				(width 0.1)
				(type default)
			)
			(layer "F.Fab")
		)
		(fp_line
			(start 0.12065 -0.3048)
			(end 0.67945 -0.3048)
			(stroke
				(width 0.1)
				(type default)
			)
			(layer "F.Fab")
		)
		(fp_line
			(start 0.120396 0.3048)
			(end 0.120396 0.2794)
			(stroke
				(width 0.1)
				(type default)
			)
			(layer "F.Fab")
		)
		(fp_line
			(start 0.120396 0.2794)
			(end -0.12065 0.2794)
			(stroke
				(width 0.1)
				(type default)
			)
			(layer "F.Fab")
		)
		(fp_line
			(start -0.12065 0.3048)
			(end -0.67945 0.3048)
			(stroke
				(width 0.1)
				(type default)
			)
			(layer "F.Fab")
		)
		(fp_line
			(start -0.12065 0.2794)
			(end -0.12065 0.3048)
			(stroke
				(width 0.1)
				(type default)
			)
			(layer "F.Fab")
		)
		(fp_line
			(start -0.12065 -0.2794)
			(end 0.12065 -0.2794)
			(stroke
				(width 0.1)
				(type default)
			)
			(layer "F.Fab")
		)
		(fp_line
			(start -0.12065 -0.305054)
			(end -0.12065 -0.2794)
			(stroke
				(width 0.1)
				(type default)
			)
			(layer "F.Fab")
		)
		(fp_line
			(start -0.67945 0.3048)
			(end -0.67945 -0.305054)
			(stroke
				(width 0.1)
				(type default)
			)
			(layer "F.Fab")
		)
		(fp_line
			(start -0.67945 -0.305054)
			(end -0.12065 -0.305054)
			(stroke
				(width 0.1)
				(type default)
			)
			(layer "F.Fab")
		)
		(pad "1" smd circle
			(at -0.40005 0 180)
			(size 0 0)
			(layers "F.Cu" "F.Mask" "F.Paste")
			(net "ADC128_A1")
		)
		(pad "2" smd circle
			(at 0.40005 0 180)
			(size 0 0)
			(layers "F.Cu" "F.Mask" "F.Paste")
			(net "GND")
		)
	)
	(footprint ""
		(layer "F.Cu")
		(at 139.374626 -408.517344 -90)
		(property "Reference" "C6710"
			(at 0 0 270)
			(layer "F.SilkS")
			(hide yes)
			(effects
				(font
					(size 1.27 1.27)
				)
			)
		)
		(property "Value" ""
			(at 0 0 270)
			(layer "F.Fab")
			(effects
				(font
					(size 1.27 1.27)
				)
			)
		)
		(duplicate_pad_numbers_are_jumpers no)
		(fp_line
			(start -0.299974 0.150114)
			(end -0.299974 -0.150114)
			(stroke
				(width 0.1)
				(type default)
			)
			(layer "F.Fab")
		)
		(fp_line
			(start 0.299974 0.150114)
			(end -0.299974 0.150114)
			(stroke
				(width 0.1)
				(type default)
			)
			(layer "F.Fab")
		)
		(fp_line
			(start -0.299974 -0.150114)
			(end 0.299974 -0.150114)
			(stroke
				(width 0.1)
				(type default)
			)
			(layer "F.Fab")
		)
		(fp_line
			(start 0.299974 -0.150114)
			(end 0.299974 0.150114)
			(stroke
				(width 0.1)
				(type default)
			)
			(layer "F.Fab")
		)
		(pad "1" smd rect
			(at -0.2667 0 270)
			(size 0.3048 0.381)
			(layers "F.Cu" "F.Mask" "F.Paste")
			(net "P5E_CPU1_P2_TX_BUF_C_DN<8>")
		)
		(pad "2" smd rect
			(at 0.2667 0 270)
			(size 0.3048 0.381)
			(layers "F.Cu" "F.Mask" "F.Paste")
			(net "P5E_CPU1_P2_TX_BUF_DN<8>")
		)
	)
)
